# BASEBOARD_FAB2 (Tioga Pass) — schematic netlist excerpt (pin names and nets, part order shuffled) for the footprints in the layout excerpt that follows; sources: Cadence DE-HDL packaged netlist, KiCad conversion of Wiwynn_Tioga_Pass_MB.brd

R8E34  RES  10.0K 1% CHIP  pkg 0402  page 240 : A = VSENSE_VOUT_P3V3_STBY ; B = AGND_P3V3_STBY
C7W5  SC22U16V5MX-4-GP  20%  pkg SMD-BCG5  page 220 : \1\ = VR_FET_SW_P12V_STBY_PVDDQ_DEF ; \2\ = GND
CT59  CAP  1000PF 50V 10% X7R  pkg 0402LF  page 205 : A = VR_PVSA_CPU0_PHASE_SW ; B = VR_PVSA_CPU0_PHASE_SW_RC

(kicad_pcb
	(version 20260206)
	(generator "pcbnew")
	(generator_version "10.0")
	(general
		(thickness 1.6)
		(legacy_teardrops no)
	)
	(paper "A4")
	(title_block
		(title "Wiwynn_Tioga_Pass_MB.brd")
		(comment 1 "Tioga Pass / footprints 1451-1453 of 4770")
	)
	(layers
		(0 "F.Cu" signal "TOP")
		(4 "In1.Cu" signal "L2GND")
		(6 "In2.Cu" signal "L3")
		(8 "In3.Cu" signal "L4GND")
		(10 "In4.Cu" signal "L5")
		(12 "In5.Cu" signal "L6GND")
		(14 "In6.Cu" signal "L7VCC")
		(16 "In7.Cu" signal "L8VCC")
		(18 "In8.Cu" signal "L9GND")
		(20 "In9.Cu" signal "L10")
		(22 "In10.Cu" signal "L11GND")
		(24 "In11.Cu" signal "L12")
		(26 "In12.Cu" signal "L13GND")
		(2 "B.Cu" signal "BOTTOM")
		(9 "F.Adhes" user "F.Adhesive")
		(11 "B.Adhes" user "B.Adhesive")
		(13 "F.Paste" user "Package Geometry/Pastemask Top")
		(15 "B.Paste" user "Package Geometry/Pastemask Bottom")
		(5 "F.SilkS" user "Ref Des/Silkscreen Top")
		(7 "B.SilkS" user "Ref Des/Silkscreen Bottom")
		(1 "F.Mask" user "Board Geometry/Soldermask Top")
		(3 "B.Mask" user "Board Geometry/Soldermask Bottom")
		(17 "Dwgs.User" user "User.Drawings")
		(19 "Cmts.User" user "User.Comments")
		(21 "Eco1.User" user "User.Eco1")
		(23 "Eco2.User" user "User.Eco2")
		(25 "Edge.Cuts" user "Board Geometry/Outline")
		(27 "Margin" user)
		(31 "F.CrtYd" user "Package Geometry/Place Bound Top")
		(29 "B.CrtYd" user "Package Geometry/Place Bound Bottom")
		(35 "F.Fab" user "Ref Des/Assembly Top")
		(33 "B.Fab" user "Ref Des/Assembly Bottom")
	)
	(footprint ""
		(layer "F.Cu")
		(at 204.649832 -93.36024 -90)
		(property "Reference" "CT59"
			(at -0.8382 -0.67818 270)
			(unlocked yes)
			(layer "F.SilkS")
			(effects
				(font
					(size 0.4064 0.254)
					(thickness 0.1524)
				)
				(justify left)
			)
		)
		(property "Value" ""
			(at 0 0 270)
			(layer "F.Fab")
			(effects
				(font
					(size 1.27 1.27)
				)
			)
		)
		(duplicate_pad_numbers_are_jumpers no)
		(fp_poly
			(pts
				(xy 0.3048 -0.1016) (xy 0.3048 0.9906) (xy -0.3048 0.9906) (xy -0.3048 -0.1016)
			)
			(stroke
				(width 0)
				(type default)
			)
			(fill no)
			(layer "F.CrtYd")
		)
		(fp_line
			(start -0.3048 0.9906)
			(end 0.3048 0.9906)
			(stroke
				(width 0.1)
				(type default)
			)
			(layer "F.Fab")
		)
		(fp_line
			(start 0.3048 0.9906)
			(end 0.3048 -0.1016)
			(stroke
				(width 0.1)
				(type default)
			)
			(layer "F.Fab")
		)
		(fp_line
			(start -0.3048 -0.1016)
			(end -0.3048 0.9906)
			(stroke
				(width 0.1)
				(type default)
			)
			(layer "F.Fab")
		)
		(fp_line
			(start 0.3048 -0.1016)
			(end -0.3048 -0.1016)
			(stroke
				(width 0.1)
				(type default)
			)
			(layer "F.Fab")
		)
		(pad "1" smd rect
			(at 0 0 270)
			(size 0.508 0.508)
			(layers "F.Cu" "F.Mask" "F.Paste")
			(net "VR_PVSA_CPU0_PHASE_SW")
		)
		(pad "2" smd rect
			(at 0 0.889 270)
			(size 0.508 0.508)
			(layers "F.Cu" "F.Mask" "F.Paste")
			(net "VR_PVSA_CPU0_PHASE_SW_RC")
		)
		(zone
			(layer "F.Cu")
			(hatch none 0.5)
			(connect_pads
				(clearance 0)
			)
			(min_thickness 0.25)
			(keepout
				(tracks not_allowed)
				(vias allowed)
				(pads allowed)
				(copperpour not_allowed)
				(footprints allowed)
			)
			(placement
				(enabled no)
				(sheetname "")
			)
			(fill
				(thermal_gap 0.5)
				(thermal_bridge_width 0.5)
				(island_removal_mode 0)
			)
			(polygon
				(pts
					(xy 204.014832 -93.61424) (xy 204.014832 -93.10624) (xy 204.395832 -93.10624) (xy 204.395832 -93.61424)
				)
			)
		)
		(zone
			(layer "F.Cu")
			(hatch none 0.5)
			(connect_pads
				(clearance 0)
			)
			(min_thickness 0.25)
			(keepout
				(tracks allowed)
				(vias not_allowed)
				(pads allowed)
				(copperpour not_allowed)
				(footprints allowed)
			)
			(placement
				(enabled no)
				(sheetname "")
			)
			(fill
				(thermal_gap 0.5)
				(thermal_bridge_width 0.5)
				(island_removal_mode 0)
			)
			(polygon
				(pts
					(xy 204.395832 -93.61424) (xy 204.395832 -93.10624) (xy 204.014832 -93.10624) (xy 204.014832 -93.61424)
				)
			)
		)
	)
	(footprint ""
		(layer "F.Cu")
		(at 366.154716 -147.914106)
		(property "Reference" "C7W5"
			(at 0 0 0)
			(layer "F.SilkS")
			(hide yes)
			(effects
				(font
					(size 1.27 1.27)
				)
			)
		)
		(property "Value" "*"
			(at -0.0762 -6.2357 0)
			(unlocked yes)
			(layer "F.Fab")
			(hide yes)
			(effects
				(font
					(size 1.27 1.016)
					(thickness 0.1524)
				)
			)
		)
		(property "Device Type" "SC22U16V5MX-4-GP_SMD-BCG5-SC22A"
			(at -0.0762 -8.2677 0)
			(unlocked yes)
			(layer "F.Fab")
			(hide yes)
			(effects
				(font
					(size 1.27 1.016)
					(thickness 0.1524)
				)
			)
		)
		(duplicate_pad_numbers_are_jumpers no)
		(fp_line
			(start 0.635 0)
			(end -0.635 0)
			(stroke
				(width 0.508)
				(type default)
			)
			(layer "F.SilkS")
		)
		(fp_rect
			(start -0.9652 1.778)
			(end 0.9652 -1.778)
			(stroke
				(width 0)
				(type default)
			)
			(fill no)
			(layer "F.CrtYd")
		)
		(fp_poly
			(pts
				(xy -0.9652 -1.778) (xy 0.9652 -1.778) (xy 0.9652 1.778) (xy -0.9652 1.778)
			)
			(stroke
				(width 0)
				(type default)
			)
			(fill no)
			(layer "F.Fab")
		)
		(pad "1" smd rect
			(at 0 -0.9652)
			(size 1.397 1.143)
			(layers "F.Cu" "F.Mask" "F.Paste")
			(net "VR_FET_SW_P12V_STBY_PVDDQ_DEF")
		)
		(pad "2" smd rect
			(at 0 0.9652)
			(size 1.397 1.143)
			(layers "F.Cu" "F.Mask" "F.Paste")
			(net "GND")
		)
	)
	(footprint ""
		(layer "F.Cu")
		(at 466.476842 -25.77846 -90)
		(property "Reference" "R8E34"
			(at 0 0 270)
			(layer "F.SilkS")
			(hide yes)
			(effects
				(font
					(size 1.27 1.27)
				)
			)
		)
		(property "Value" ""
			(at 0 0 270)
			(layer "F.Fab")
			(effects
				(font
					(size 1.27 1.27)
				)
			)
		)
		(duplicate_pad_numbers_are_jumpers no)
		(fp_rect
			(start 0.2794 -0.1016)
			(end -0.2794 0.9906)
			(stroke
				(width 0)
				(type default)
			)
			(fill no)
			(layer "F.CrtYd")
		)
		(fp_line
			(start -0.2794 0.9906)
			(end 0.2794 0.9906)
			(stroke
				(width 0.1)
				(type default)
			)
			(layer "F.Fab")
		)
		(fp_line
			(start 0.2794 0.9906)
			(end 0.2794 -0.1016)
			(stroke
				(width 0.1)
				(type default)
			)
			(layer "F.Fab")
		)
		(fp_line
			(start -0.2794 -0.1016)
			(end -0.2794 0.9906)
			(stroke
				(width 0.1)
				(type default)
			)
			(layer "F.Fab")
		)
		(fp_line
			(start 0.2794 -0.1016)
			(end -0.2794 -0.1016)
			(stroke
				(width 0.1)
				(type default)
			)
			(layer "F.Fab")
		)
		(pad "1" smd rect
			(at 0 0 270)
			(size 0.508 0.508)
			(layers "F.Cu" "F.Mask" "F.Paste")
			(net "VSENSE_VOUT_P3V3_STBY")
		)
		(pad "2" smd rect
			(at 0 0.889 270)
			(size 0.508 0.508)
			(layers "F.Cu" "F.Mask" "F.Paste")
			(net "AGND_P3V3_STBY")
		)
		(zone
			(layer "F.Cu")
			(hatch none 0.5)
			(connect_pads
				(clearance 0)
			)
			(min_thickness 0.25)
			(keepout
				(tracks not_allowed)
				(vias allowed)
				(pads allowed)
				(copperpour not_allowed)
				(footprints allowed)
			)
			(placement
				(enabled no)
				(sheetname "")
			)
			(fill
				(thermal_gap 0.5)
				(thermal_bridge_width 0.5)
				(island_removal_mode 0)
			)
			(polygon
				(pts
					(xy 466.222842 -25.52446) (xy 466.222842 -26.03246) (xy 465.841842 -26.03246) (xy 465.841842 -25.52446)
				)
			)
		)
		(zone
			(layer "F.Cu")
			(hatch none 0.5)
			(connect_pads
				(clearance 0)
			)
			(min_thickness 0.25)
			(keepout
				(tracks allowed)
				(vias not_allowed)
				(pads allowed)
				(copperpour not_allowed)
				(footprints allowed)
			)
			(placement
				(enabled no)
				(sheetname "")
			)
			(fill
				(thermal_gap 0.5)
				(thermal_bridge_width 0.5)
				(island_removal_mode 0)
			)
			(polygon
				(pts
					(xy 466.222842 -25.52446) (xy 466.222842 -26.03246) (xy 465.841842 -26.03246) (xy 465.841842 -25.52446)
				)
			)
		)
	)
)
